(kicad_pcb
	(version 20260206)
	(generator "pcbnew")
	(generator_version "10.0")
	(general
		(thickness 1.6)
		(legacy_teardrops no)
	)
	(paper "A4")
	(title_block
		(title "12092022_DA0F0TMDCD0_F0T_Management_Board_D_brd_V3_OCP.brd")
		(comment 1 "Grand Teton / footprints 449-454 of 1440")
	)
	(layers
		(0 "F.Cu" signal "TOP")
		(4 "In1.Cu" signal "GND")
		(6 "In2.Cu" signal "IN1")
		(8 "In3.Cu" signal "GND1")
		(10 "In4.Cu" signal "IN2")
		(12 "In5.Cu" signal "VCC")
		(14 "In6.Cu" signal "VCC1")
		(16 "In7.Cu" signal "IN3")
		(18 "In8.Cu" signal "GND2")
		(20 "In9.Cu" signal "IN4")
		(22 "In10.Cu" signal "GND3")
		(2 "B.Cu" signal "BOTTOM")
		(9 "F.Adhes" user "F.Adhesive")
		(11 "B.Adhes" user "B.Adhesive")
		(13 "F.Paste" user "Package Geometry/Pastemask Top")
		(15 "B.Paste" user "Package Geometry/Pastemask Bottom")
		(5 "F.SilkS" user "Ref Des/Silkscreen Top")
		(7 "B.SilkS" user "Ref Des/Silkscreen Bottom")
		(1 "F.Mask" user "Board Geometry/Soldermask Top")
		(3 "B.Mask" user "Board Geometry/Soldermask Bottom")
		(17 "Dwgs.User" user "User.Drawings")
		(19 "Cmts.User" user "User.Comments")
		(21 "Eco1.User" user "User.Eco1")
		(23 "Eco2.User" user "User.Eco2")
		(25 "Edge.Cuts" user "Board Geometry/Outline")
		(27 "Margin" user)
		(31 "F.CrtYd" user "Package Geometry/Place Bound Top")
		(29 "B.CrtYd" user "Package Geometry/Place Bound Bottom")
		(35 "F.Fab" user "Ref Des/Assembly Top")
		(33 "B.Fab" user "Ref Des/Assembly Bottom")
	)
	(footprint ""
		(layer "F.Cu")
		(at 16.4846 -83.693 -90)
		(property "Reference" "R436"
			(at 0 0 270)
			(layer "F.SilkS")
			(hide yes)
			(effects
				(font
					(size 1.27 1.27)
				)
			)
		)
		(property "Value" ""
			(at 0 0 270)
			(layer "F.Fab")
			(effects
				(font
					(size 1.27 1.27)
				)
			)
		)
		(duplicate_pad_numbers_are_jumpers no)
		(fp_line
			(start -0.7874 0.4064)
			(end -0.7874 -0.4064)
			(stroke
				(width 0.1524)
				(type default)
			)
			(layer "F.SilkS")
		)
		(fp_line
			(start 0.7874 0.4064)
			(end -0.7874 0.4064)
			(stroke
				(width 0.1524)
				(type default)
			)
			(layer "F.SilkS")
		)
		(fp_line
			(start -0.7874 -0.4064)
			(end 0.7874 -0.4064)
			(stroke
				(width 0.1524)
				(type default)
			)
			(layer "F.SilkS")
		)
		(fp_line
			(start 0.7874 -0.4064)
			(end 0.7874 0.4064)
			(stroke
				(width 0.1524)
				(type default)
			)
			(layer "F.SilkS")
		)
		(fp_line
			(start -0.67945 0.3048)
			(end -0.67945 -0.305054)
			(stroke
				(width 0.1)
				(type default)
			)
			(layer "F.Fab")
		)
		(fp_line
			(start -0.12065 0.3048)
			(end -0.67945 0.3048)
			(stroke
				(width 0.1)
				(type default)
			)
			(layer "F.Fab")
		)
		(fp_line
			(start 0.120396 0.3048)
			(end 0.120396 0.2794)
			(stroke
				(width 0.1)
				(type default)
			)
			(layer "F.Fab")
		)
		(fp_line
			(start 0.67945 0.3048)
			(end 0.120396 0.3048)
			(stroke
				(width 0.1)
				(type default)
			)
			(layer "F.Fab")
		)
		(fp_line
			(start -0.12065 0.2794)
			(end -0.12065 0.3048)
			(stroke
				(width 0.1)
				(type default)
			)
			(layer "F.Fab")
		)
		(fp_line
			(start 0.120396 0.2794)
			(end -0.12065 0.2794)
			(stroke
				(width 0.1)
				(type default)
			)
			(layer "F.Fab")
		)
		(fp_line
			(start -0.12065 -0.2794)
			(end 0.12065 -0.2794)
			(stroke
				(width 0.1)
				(type default)
			)
			(layer "F.Fab")
		)
		(fp_line
			(start 0.12065 -0.2794)
			(end 0.12065 -0.3048)
			(stroke
				(width 0.1)
				(type default)
			)
			(layer "F.Fab")
		)
		(fp_line
			(start 0.12065 -0.3048)
			(end 0.67945 -0.3048)
			(stroke
				(width 0.1)
				(type default)
			)
			(layer "F.Fab")
		)
		(fp_line
			(start 0.67945 -0.3048)
			(end 0.67945 0.3048)
			(stroke
				(width 0.1)
				(type default)
			)
			(layer "F.Fab")
		)
		(fp_line
			(start -0.67945 -0.305054)
			(end -0.12065 -0.305054)
			(stroke
				(width 0.1)
				(type default)
			)
			(layer "F.Fab")
		)
		(fp_line
			(start -0.12065 -0.305054)
			(end -0.12065 -0.2794)
			(stroke
				(width 0.1)
				(type default)
			)
			(layer "F.Fab")
		)
		(pad "1" smd circle
			(at -0.40005 0 270)
			(size 0 0)
			(layers "F.Cu" "F.Mask" "F.Paste")
			(net "SGPIO_PLD_LD_0")
		)
		(pad "2" smd circle
			(at 0.40005 0 270)
			(size 0 0)
			(layers "F.Cu" "F.Mask" "F.Paste")
			(net "SGPIO_LD_0")
		)
	)
	(footprint ""
		(layer "F.Cu")
		(at 23.1775 -104.775)
		(property "Reference" "C173"
			(at 0 0 0)
			(layer "F.SilkS")
			(hide yes)
			(effects
				(font
					(size 1.27 1.27)
				)
			)
		)
		(property "Value" ""
			(at 0 0 0)
			(layer "F.Fab")
			(effects
				(font
					(size 1.27 1.27)
				)
			)
		)
		(duplicate_pad_numbers_are_jumpers no)
		(fp_line
			(start -0.7874 -0.4064)
			(end 0.7874 -0.4064)
			(stroke
				(width 0.1524)
				(type default)
			)
			(layer "F.SilkS")
		)
		(fp_line
			(start -0.7874 0.4064)
			(end -0.7874 -0.4064)
			(stroke
				(width 0.1524)
				(type default)
			)
			(layer "F.SilkS")
		)
		(fp_line
			(start 0.7874 -0.4064)
			(end 0.7874 0.4064)
			(stroke
				(width 0.1524)
				(type default)
			)
			(layer "F.SilkS")
		)
		(fp_line
			(start 0.7874 0.4064)
			(end -0.7874 0.4064)
			(stroke
				(width 0.1524)
				(type default)
			)
			(layer "F.SilkS")
		)
		(fp_line
			(start -0.67945 -0.305054)
			(end -0.12065 -0.305054)
			(stroke
				(width 0.1)
				(type default)
			)
			(layer "F.Fab")
		)
		(fp_line
			(start -0.67945 0.3048)
			(end -0.67945 -0.305054)
			(stroke
				(width 0.1)
				(type default)
			)
			(layer "F.Fab")
		)
		(fp_line
			(start -0.12065 -0.305054)
			(end -0.12065 -0.2794)
			(stroke
				(width 0.1)
				(type default)
			)
			(layer "F.Fab")
		)
		(fp_line
			(start -0.12065 -0.2794)
			(end 0.12065 -0.2794)
			(stroke
				(width 0.1)
				(type default)
			)
			(layer "F.Fab")
		)
		(fp_line
			(start -0.12065 0.2794)
			(end -0.12065 0.3048)
			(stroke
				(width 0.1)
				(type default)
			)
			(layer "F.Fab")
		)
		(fp_line
			(start -0.12065 0.3048)
			(end -0.67945 0.3048)
			(stroke
				(width 0.1)
				(type default)
			)
			(layer "F.Fab")
		)
		(fp_line
			(start 0.120396 0.2794)
			(end -0.12065 0.2794)
			(stroke
				(width 0.1)
				(type default)
			)
			(layer "F.Fab")
		)
		(fp_line
			(start 0.120396 0.3048)
			(end 0.120396 0.2794)
			(stroke
				(width 0.1)
				(type default)
			)
			(layer "F.Fab")
		)
		(fp_line
			(start 0.12065 -0.3048)
			(end 0.67945 -0.3048)
			(stroke
				(width 0.1)
				(type default)
			)
			(layer "F.Fab")
		)
		(fp_line
			(start 0.12065 -0.2794)
			(end 0.12065 -0.3048)
			(stroke
				(width 0.1)
				(type default)
			)
			(layer "F.Fab")
		)
		(fp_line
			(start 0.67945 -0.3048)
			(end 0.67945 0.3048)
			(stroke
				(width 0.1)
				(type default)
			)
			(layer "F.Fab")
		)
		(fp_line
			(start 0.67945 0.3048)
			(end 0.120396 0.3048)
			(stroke
				(width 0.1)
				(type default)
			)
			(layer "F.Fab")
		)
		(pad "1" smd circle
			(at -0.40005 0)
			(size 0 0)
			(layers "F.Cu" "F.Mask" "F.Paste")
			(net "RST_BMC_SELF_HW_D_C")
		)
		(pad "2" smd circle
			(at 0.40005 0)
			(size 0 0)
			(layers "F.Cu" "F.Mask" "F.Paste")
			(net "GND")
		)
	)
	(footprint ""
		(layer "F.Cu")
		(at 11.612626 -47.63135)
		(property "Reference" "PR525"
			(at 0 0 0)
			(layer "F.SilkS")
			(hide yes)
			(effects
				(font
					(size 1.27 1.27)
				)
			)
		)
		(property "Value" ""
			(at 0 0 0)
			(layer "F.Fab")
			(effects
				(font
					(size 1.27 1.27)
				)
			)
		)
		(duplicate_pad_numbers_are_jumpers no)
		(fp_line
			(start -0.7874 -0.4064)
			(end 0.7874 -0.4064)
			(stroke
				(width 0.1524)
				(type default)
			)
			(layer "F.SilkS")
		)
		(fp_line
			(start -0.7874 0.4064)
			(end -0.7874 -0.4064)
			(stroke
				(width 0.1524)
				(type default)
			)
			(layer "F.SilkS")
		)
		(fp_line
			(start 0.7874 -0.4064)
			(end 0.7874 0.4064)
			(stroke
				(width 0.1524)
				(type default)
			)
			(layer "F.SilkS")
		)
		(fp_line
			(start 0.7874 0.4064)
			(end -0.7874 0.4064)
			(stroke
				(width 0.1524)
				(type default)
			)
			(layer "F.SilkS")
		)
		(fp_line
			(start -0.67945 -0.305054)
			(end -0.12065 -0.305054)
			(stroke
				(width 0.1)
				(type default)
			)
			(layer "F.Fab")
		)
		(fp_line
			(start -0.67945 0.3048)
			(end -0.67945 -0.305054)
			(stroke
				(width 0.1)
				(type default)
			)
			(layer "F.Fab")
		)
		(fp_line
			(start -0.12065 -0.305054)
			(end -0.12065 -0.2794)
			(stroke
				(width 0.1)
				(type default)
			)
			(layer "F.Fab")
		)
		(fp_line
			(start -0.12065 -0.2794)
			(end 0.12065 -0.2794)
			(stroke
				(width 0.1)
				(type default)
			)
			(layer "F.Fab")
		)
		(fp_line
			(start -0.12065 0.2794)
			(end -0.12065 0.3048)
			(stroke
				(width 0.1)
				(type default)
			)
			(layer "F.Fab")
		)
		(fp_line
			(start -0.12065 0.3048)
			(end -0.67945 0.3048)
			(stroke
				(width 0.1)
				(type default)
			)
			(layer "F.Fab")
		)
		(fp_line
			(start 0.120396 0.2794)
			(end -0.12065 0.2794)
			(stroke
				(width 0.1)
				(type default)
			)
			(layer "F.Fab")
		)
		(fp_line
			(start 0.120396 0.3048)
			(end 0.120396 0.2794)
			(stroke
				(width 0.1)
				(type default)
			)
			(layer "F.Fab")
		)
		(fp_line
			(start 0.12065 -0.3048)
			(end 0.67945 -0.3048)
			(stroke
				(width 0.1)
				(type default)
			)
			(layer "F.Fab")
		)
		(fp_line
			(start 0.12065 -0.2794)
			(end 0.12065 -0.3048)
			(stroke
				(width 0.1)
				(type default)
			)
			(layer "F.Fab")
		)
		(fp_line
			(start 0.67945 -0.3048)
			(end 0.67945 0.3048)
			(stroke
				(width 0.1)
				(type default)
			)
			(layer "F.Fab")
		)
		(fp_line
			(start 0.67945 0.3048)
			(end 0.120396 0.3048)
			(stroke
				(width 0.1)
				(type default)
			)
			(layer "F.Fab")
		)
		(pad "1" smd circle
			(at -0.40005 0)
			(size 0 0)
			(layers "F.Cu" "F.Mask" "F.Paste")
			(net "P5V_AUX_CS")
		)
		(pad "2" smd circle
			(at 0.40005 0)
			(size 0 0)
			(layers "F.Cu" "F.Mask" "F.Paste")
			(net "GND")
		)
	)
	(footprint ""
		(layer "F.Cu")
		(at 77.707744 -35.527488 90)
		(property "Reference" "R330"
			(at 0 0 90)
			(layer "F.SilkS")
			(hide yes)
			(effects
				(font
					(size 1.27 1.27)
				)
			)
		)
		(property "Value" ""
			(at 0 0 90)
			(layer "F.Fab")
			(effects
				(font
					(size 1.27 1.27)
				)
			)
		)
		(duplicate_pad_numbers_are_jumpers no)
		(fp_line
			(start 0.7874 -0.4064)
			(end 0.7874 0.4064)
			(stroke
				(width 0.1524)
				(type default)
			)
			(layer "F.SilkS")
		)
		(fp_line
			(start -0.7874 -0.4064)
			(end 0.7874 -0.4064)
			(stroke
				(width 0.1524)
				(type default)
			)
			(layer "F.SilkS")
		)
		(fp_line
			(start 0.7874 0.4064)
			(end -0.7874 0.4064)
			(stroke
				(width 0.1524)
				(type default)
			)
			(layer "F.SilkS")
		)
		(fp_line
			(start -0.7874 0.4064)
			(end -0.7874 -0.4064)
			(stroke
				(width 0.1524)
				(type default)
			)
			(layer "F.SilkS")
		)
		(fp_line
			(start -0.12065 -0.305054)
			(end -0.12065 -0.2794)
			(stroke
				(width 0.1)
				(type default)
			)
			(layer "F.Fab")
		)
		(fp_line
			(start -0.67945 -0.305054)
			(end -0.12065 -0.305054)
			(stroke
				(width 0.1)
				(type default)
			)
			(layer "F.Fab")
		)
		(fp_line
			(start 0.67945 -0.3048)
			(end 0.67945 0.3048)
			(stroke
				(width 0.1)
				(type default)
			)
			(layer "F.Fab")
		)
		(fp_line
			(start 0.12065 -0.3048)
			(end 0.67945 -0.3048)
			(stroke
				(width 0.1)
				(type default)
			)
			(layer "F.Fab")
		)
		(fp_line
			(start 0.12065 -0.2794)
			(end 0.12065 -0.3048)
			(stroke
				(width 0.1)
				(type default)
			)
			(layer "F.Fab")
		)
		(fp_line
			(start -0.12065 -0.2794)
			(end 0.12065 -0.2794)
			(stroke
				(width 0.1)
				(type default)
			)
			(layer "F.Fab")
		)
		(fp_line
			(start 0.120396 0.2794)
			(end -0.12065 0.2794)
			(stroke
				(width 0.1)
				(type default)
			)
			(layer "F.Fab")
		)
		(fp_line
			(start -0.12065 0.2794)
			(end -0.12065 0.3048)
			(stroke
				(width 0.1)
				(type default)
			)
			(layer "F.Fab")
		)
		(fp_line
			(start 0.67945 0.3048)
			(end 0.120396 0.3048)
			(stroke
				(width 0.1)
				(type default)
			)
			(layer "F.Fab")
		)
		(fp_line
			(start 0.120396 0.3048)
			(end 0.120396 0.2794)
			(stroke
				(width 0.1)
				(type default)
			)
			(layer "F.Fab")
		)
		(fp_line
			(start -0.12065 0.3048)
			(end -0.67945 0.3048)
			(stroke
				(width 0.1)
				(type default)
			)
			(layer "F.Fab")
		)
		(fp_line
			(start -0.67945 0.3048)
			(end -0.67945 -0.305054)
			(stroke
				(width 0.1)
				(type default)
			)
			(layer "F.Fab")
		)
		(pad "1" smd circle
			(at -0.40005 0 90)
			(size 0 0)
			(layers "F.Cu" "F.Mask" "F.Paste")
			(net "GND")
		)
		(pad "2" smd circle
			(at 0.40005 0 90)
			(size 0 0)
			(layers "F.Cu" "F.Mask" "F.Paste")
			(net "M_BMC_DDR4_MA<4>")
		)
	)
	(footprint ""
		(layer "F.Cu")
		(at 24.7142 -65.8622 -90)
		(property "Reference" "R742"
			(at 0 0 270)
			(layer "F.SilkS")
			(hide yes)
			(effects
				(font
					(size 1.27 1.27)
				)
			)
		)
		(property "Value" ""
			(at 0 0 270)
			(layer "F.Fab")
			(effects
				(font
					(size 1.27 1.27)
				)
			)
		)
		(duplicate_pad_numbers_are_jumpers no)
		(fp_line
			(start -0.7874 0.4064)
			(end -0.7874 -0.4064)
			(stroke
				(width 0.1524)
				(type default)
			)
			(layer "F.SilkS")
		)
		(fp_line
			(start 0.7874 0.4064)
			(end -0.7874 0.4064)
			(stroke
				(width 0.1524)
				(type default)
			)
			(layer "F.SilkS")
		)
		(fp_line
			(start -0.7874 -0.4064)
			(end 0.7874 -0.4064)
			(stroke
				(width 0.1524)
				(type default)
			)
			(layer "F.SilkS")
		)
		(fp_line
			(start 0.7874 -0.4064)
			(end 0.7874 0.4064)
			(stroke
				(width 0.1524)
				(type default)
			)
			(layer "F.SilkS")
		)
		(fp_line
			(start -0.67945 0.3048)
			(end -0.67945 -0.305054)
			(stroke
				(width 0.1)
				(type default)
			)
			(layer "F.Fab")
		)
		(fp_line
			(start -0.12065 0.3048)
			(end -0.67945 0.3048)
			(stroke
				(width 0.1)
				(type default)
			)
			(layer "F.Fab")
		)
		(fp_line
			(start 0.120396 0.3048)
			(end 0.120396 0.2794)
			(stroke
				(width 0.1)
				(type default)
			)
			(layer "F.Fab")
		)
		(fp_line
			(start 0.67945 0.3048)
			(end 0.120396 0.3048)
			(stroke
				(width 0.1)
				(type default)
			)
			(layer "F.Fab")
		)
		(fp_line
			(start -0.12065 0.2794)
			(end -0.12065 0.3048)
			(stroke
				(width 0.1)
				(type default)
			)
			(layer "F.Fab")
		)
		(fp_line
			(start 0.120396 0.2794)
			(end -0.12065 0.2794)
			(stroke
				(width 0.1)
				(type default)
			)
			(layer "F.Fab")
		)
		(fp_line
			(start -0.12065 -0.2794)
			(end 0.12065 -0.2794)
			(stroke
				(width 0.1)
				(type default)
			)
			(layer "F.Fab")
		)
		(fp_line
			(start 0.12065 -0.2794)
			(end 0.12065 -0.3048)
			(stroke
				(width 0.1)
				(type default)
			)
			(layer "F.Fab")
		)
		(fp_line
			(start 0.12065 -0.3048)
			(end 0.67945 -0.3048)
			(stroke
				(width 0.1)
				(type default)
			)
			(layer "F.Fab")
		)
		(fp_line
			(start 0.67945 -0.3048)
			(end 0.67945 0.3048)
			(stroke
				(width 0.1)
				(type default)
			)
			(layer "F.Fab")
		)
		(fp_line
			(start -0.67945 -0.305054)
			(end -0.12065 -0.305054)
			(stroke
				(width 0.1)
				(type default)
			)
			(layer "F.Fab")
		)
		(fp_line
			(start -0.12065 -0.305054)
			(end -0.12065 -0.2794)
			(stroke
				(width 0.1)
				(type default)
			)
			(layer "F.Fab")
		)
		(pad "1" smd circle
			(at -0.40005 0 270)
			(size 0 0)
			(layers "F.Cu" "F.Mask" "F.Paste")
			(net "P3V3_AUX")
		)
		(pad "2" smd circle
			(at 0.40005 0 270)
			(size 0 0)
			(layers "F.Cu" "F.Mask" "F.Paste")
			(net "SPA_SOUT_SW_BUF")
		)
	)
	(footprint ""
		(layer "F.Cu")
		(at 40.0304 -109.474 -90)
		(property "Reference" "R75"
			(at 0 0 270)
			(layer "F.SilkS")
			(hide yes)
			(effects
				(font
					(size 1.27 1.27)
				)
			)
		)
		(property "Value" ""
			(at 0 0 270)
			(layer "F.Fab")
			(effects
				(font
					(size 1.27 1.27)
				)
			)
		)
		(duplicate_pad_numbers_are_jumpers no)
		(fp_line
			(start -0.7874 0.4064)
			(end -0.7874 -0.4064)
			(stroke
				(width 0.1524)
				(type default)
			)
			(layer "F.SilkS")
		)
		(fp_line
			(start 0.7874 0.4064)
			(end -0.7874 0.4064)
			(stroke
				(width 0.1524)
				(type default)
			)
			(layer "F.SilkS")
		)
		(fp_line
			(start -0.7874 -0.4064)
			(end 0.7874 -0.4064)
			(stroke
				(width 0.1524)
				(type default)
			)
			(layer "F.SilkS")
		)
		(fp_line
			(start 0.7874 -0.4064)
			(end 0.7874 0.4064)
			(stroke
				(width 0.1524)
				(type default)
			)
			(layer "F.SilkS")
		)
		(fp_line
			(start -0.67945 0.3048)
			(end -0.67945 -0.305054)
			(stroke
				(width 0.1)
				(type default)
			)
			(layer "F.Fab")
		)
		(fp_line
			(start -0.12065 0.3048)
			(end -0.67945 0.3048)
			(stroke
				(width 0.1)
				(type default)
			)
			(layer "F.Fab")
		)
		(fp_line
			(start 0.120396 0.3048)
			(end 0.120396 0.2794)
			(stroke
				(width 0.1)
				(type default)
			)
			(layer "F.Fab")
		)
		(fp_line
			(start 0.67945 0.3048)
			(end 0.120396 0.3048)
			(stroke
				(width 0.1)
				(type default)
			)
			(layer "F.Fab")
		)
		(fp_line
			(start -0.12065 0.2794)
			(end -0.12065 0.3048)
			(stroke
				(width 0.1)
				(type default)
			)
			(layer "F.Fab")
		)
		(fp_line
			(start 0.120396 0.2794)
			(end -0.12065 0.2794)
			(stroke
				(width 0.1)
				(type default)
			)
			(layer "F.Fab")
		)
		(fp_line
			(start -0.12065 -0.2794)
			(end 0.12065 -0.2794)
			(stroke
				(width 0.1)
				(type default)
			)
			(layer "F.Fab")
		)
		(fp_line
			(start 0.12065 -0.2794)
			(end 0.12065 -0.3048)
			(stroke
				(width 0.1)
				(type default)
			)
			(layer "F.Fab")
		)
		(fp_line
			(start 0.12065 -0.3048)
			(end 0.67945 -0.3048)
			(stroke
				(width 0.1)
				(type default)
			)
			(layer "F.Fab")
		)
		(fp_line
			(start 0.67945 -0.3048)
			(end 0.67945 0.3048)
			(stroke
				(width 0.1)
				(type default)
			)
			(layer "F.Fab")
		)
		(fp_line
			(start -0.67945 -0.305054)
			(end -0.12065 -0.305054)
			(stroke
				(width 0.1)
				(type default)
			)
			(layer "F.Fab")
		)
		(fp_line
			(start -0.12065 -0.305054)
			(end -0.12065 -0.2794)
			(stroke
				(width 0.1)
				(type default)
			)
			(layer "F.Fab")
		)
		(pad "1" smd circle
			(at -0.40005 0 270)
			(size 0 0)
			(layers "F.Cu" "F.Mask" "F.Paste")
			(net "P3V3_AUX")
		)
		(pad "2" smd circle
			(at 0.40005 0 270)
			(size 0 0)
			(layers "F.Cu" "F.Mask" "F.Paste")
			(net "SGPIO_DO_1")
		)
	)
)
